# discovery-power-board-v1-revB — CONN_02x03_4.2mm.kicad_mod (kicad-footprint)
(module CONN_02x03_4.2mm (layer F.Cu) 
  (fp_text reference REF** (at 11.6205 0.9144) (layer F.SilkS)
    (effects (font (size 1 1) (thickness 0.15)))
  )
  (fp_text value CONN_02x03_4.2mm (at 6.8961 -11.176) (layer F.Fab)
    (effects (font (size 0.75 0.75) (thickness 0.125)))
  )
  (fp_line (start 13.8 -9.6) (end 0 -9.6) (layer F.SilkS) (width 0.1))
  (fp_line (start 13.8 0) (end 13.8 -9.6) (layer F.SilkS) (width 0.1))
  (fp_line (start 0 0) (end 13.8 0) (layer F.SilkS) (width 0.1))
  (fp_line (start 0 -9.6) (end 0 0) (layer F.SilkS) (width 0.1))
  (fp_line (start 7.9 -10.4) (end 7.9 -9.6) (layer F.SilkS) (width 0.1))
  (fp_line (start 5.9 -10.4) (end 7.9 -10.4) (layer F.SilkS) (width 0.1))
  (fp_line (start 5.9 -9.6) (end 5.9 -10.4) (layer F.SilkS) (width 0.1))
  (fp_line (start 17.8 -10.45) (end -4 -10.45) (layer F.CrtYd) (width 0.1))
  (fp_line (start 17.8 0.05) (end 17.8 -10.45) (layer F.CrtYd) (width 0.1))
  (fp_line (start -4 0.05) (end 17.8 0.05) (layer F.CrtYd) (width 0.1))
  (fp_line (start -4 -10.45) (end -4 0.05) (layer F.CrtYd) (width 0.1))
  (pad "" np_thru_hole circle (at -2 -7.1) (size 4 4) (drill 3.03) (layers *.Cu *.Mask))
  (pad "" np_thru_hole circle (at 15.8 -7.1) (size 4 4) (drill 3.03) (layers *.Cu *.Mask))
  (pad 1 thru_hole circle (at 11.1 -2.9) (size 2.5 2.5) (drill 1.85) (layers *.Cu *.Mask))
  (pad 2 thru_hole circle (at 6.9 -2.9) (size 2.5 2.5) (drill 1.85) (layers *.Cu *.Mask))
  (pad 3 thru_hole circle (at 2.7 -2.9) (size 2.5 2.5) (drill 1.85) (layers *.Cu *.Mask))
  (pad 4 thru_hole circle (at 11.1 -7.1) (size 2.5 2.5) (drill 1.85) (layers *.Cu *.Mask))
  (pad 5 thru_hole circle (at 6.9 -7.1) (size 2.5 2.5) (drill 1.85) (layers *.Cu *.Mask))
  (pad 6 thru_hole circle (at 2.7 -7.1) (size 2.5 2.5) (drill 1.85) (layers *.Cu *.Mask))
)
